# S9S_MB_2U (Grand Teton) — schematic netlist excerpt (pin names and nets, part order shuffled) for the footprints in the layout excerpt that follows; sources: Cadence DE-HDL packaged netlist, KiCad conversion of 03242023_DA0F0TMBIJ0_F0T_Motherboard_J_brd_V01_OCP.brd

J5  SCONN288_ADR50017P130CC  SCONN288_ADR50017-P130CC IO  pkg DDR288S_1-1VXB  page 86
  VIN_BULK0  = P12V_S3_AUX_CPU0_NVDIMM
  RFU0  = TP_CHC_CPU0_DIMM1_FRU_0
  VIN_MGMT  = P3V3_AUX
  HSCL  = I3C_SPD_DDRABCD_CPU0_LVC1_SCL_4
  HSDA  = I3C_SPD_DDRABCD_CPU0_LVC1_SDA
  VSS0  = GND
  DQ0_A  = M_C_CPU0_SA_DQ<0>
  VSS1  = GND
  DQ1_A  = M_C_CPU0_SA_DQ<1>
  VSS2  = GND
  DQS0_A_T  = M_C_CPU0_SA_DQS_DP<0>
  DQS0_A_C  = M_C_CPU0_SA_DQS_DN<0>
  VSS3  = GND
  DQ4_A  = M_C_CPU0_SA_DQ<4>
  VSS4  = GND
  DQ5_A  = M_C_CPU0_SA_DQ<5>
  VSS5  = GND
  DQ8_A  = M_C_CPU0_SA_DQ<8>
  VSS6  = GND
  DQ9_A  = M_C_CPU0_SA_DQ<9>
  VSS7  = GND
  DQS1_A_T  = M_C_CPU0_SA_DQS_DP<1>
  DQS1_A_C  = M_C_CPU0_SA_DQS_DN<1>
  VSS8  = GND
  DQ12_A  = M_C_CPU0_SA_DQ<12>
  VSS9  = GND
  DQ13_A  = M_C_CPU0_SA_DQ<13>
  VSS10  = GND
  DQ16_A  = M_C_CPU0_SA_DQ<16>
  VSS11  = GND
  DQ17_A  = M_C_CPU0_SA_DQ<17>
  VSS12  = GND
  DQS2_A_T  = M_C_CPU0_SA_DQS_DP<2>
  DQS2_A_C  = M_C_CPU0_SA_DQS_DN<2>
  VSS13  = GND
  DQ20_A  = M_C_CPU0_SA_DQ<20>
  VSS14  = GND
  DQ21_A  = M_C_CPU0_SA_DQ<21>
  VSS15  = GND
  DQ24_A  = M_C_CPU0_SA_DQ<24>
  VSS16  = GND
  DQ25_A  = M_C_CPU0_SA_DQ<25>
  VSS17  = GND
  DQS3_A_T  = M_C_CPU0_SA_DQS_DP<3>
  DQS3_A_C  = M_C_CPU0_SA_DQS_DN<3>
  VSS18  = GND
  DQ28_A  = M_C_CPU0_SA_DQ<28>
  VSS19  = GND
  DQ29_A  = M_C_CPU0_SA_DQ<29>
  VSS20  = GND
  CB0_A  = M_C_CPU0_SA_CB<0>
  VSS21  = GND
  CB1_A  = M_C_CPU0_SA_CB<1>
  VSS22  = GND
  DQS4_A_T  = M_C_CPU0_SA_DQS_DP<4>
  DQS4_A_C  = M_C_CPU0_SA_DQS_DN<4>
  VSS23  = GND
  CB4_A  = M_C_CPU0_SA_CB<4>
  VSS24  = GND
  CB5_A  = M_C_CPU0_SA_CB<5>
  VSS25  = GND
  ALERT_N  = M_C_CPU0_ALERT_N
  VSS26  = GND
  CS0_A_N  = M_C_CPU0_SA_CS_N<0>
  VSS27  = GND
  CA0_A  = M_C_CPU0_SA_CA<0>
  VSS28  = GND
  CA2_A  = M_C_CPU0_SA_CA<2>
  VSS29  = GND
  CA4_A  = M_C_CPU0_SA_CA<4>
  VSS30  = GND
  CA6_A  = M_C_CPU0_SA_CA<6>
  VSS31  = GND
  PAR_A  = M_C_CPU0_SA_PAR
  VSS32  = GND
  CA0_B  = M_C_CPU0_SB_CA<0>
  VSS33  = GND
  CA2_B  = M_C_CPU0_SB_CA<2>
  VSS34  = GND
  CA4_B  = M_C_CPU0_SB_CA<4>
  VSS35  = GND
  CA6_B  = M_C_CPU0_SB_CA<6>
  VSS36  = GND
  CS0_B_N  = M_C_CPU0_SB_CS_N<0>
  VSS37  = GND
  \lbd||rsp_a_n\  = M_C_CPU0_SA_RSP<0>
  \lbs||rsp_b_n\  = M_C_CPU0_SB_RSP<0>
  VSS38  = GND
  CB4_B  = M_C_CPU0_SB_CB<4>
  VSS39  = GND
  CB5_B  = M_C_CPU0_SB_CB<5>
  VSS40  = GND
  \dqs9_b_t||tdqs9_b_t||dbi4_b_n\  = M_C_CPU0_SB_DQS_DP<9>
  \dqs9_b_c||tdqs9_b_c\  = M_C_CPU0_SB_DQS_DN<9>
  VSS41  = GND
  CB0_B  = M_C_CPU0_SB_CB<0>
  VSS42  = GND
  CB1_B  = M_C_CPU0_SB_CB<1>
  VSS43  = GND
  DQ0_B  = M_C_CPU0_SB_DQ<0>
  VSS44  = GND
  DQ1_B  = M_C_CPU0_SB_DQ<1>
  VSS45  = GND
  DQS0_B_T  = M_C_CPU0_SB_DQS_DP<0>
  DQS0_B_C  = M_C_CPU0_SB_DQS_DN<0>
  VSS46  = GND
  DQ4_B  = M_C_CPU0_SB_DQ<4>
  VSS47  = GND
  DQ5_B  = M_C_CPU0_SB_DQ<5>
  VSS48  = GND
  DQ8_B  = M_C_CPU0_SB_DQ<8>
  VSS49  = GND
  DQ9_B  = M_C_CPU0_SB_DQ<9>
  VSS50  = GND
  DQS1_B_T  = M_C_CPU0_SB_DQS_DP<1>
  DQS1_B_C  = M_C_CPU0_SB_DQS_DN<1>
  VSS51  = GND
  DQ12_B  = M_C_CPU0_SB_DQ<12>
  VSS52  = GND
  DQ13_B  = M_C_CPU0_SB_DQ<13>
  VSS53  = GND
  DQ16_B  = M_C_CPU0_SB_DQ<16>
  VSS54  = GND
  DQ17_B  = M_C_CPU0_SB_DQ<17>
  VSS55  = GND
  DQS2_B_T  = M_C_CPU0_SB_DQS_DP<2>
  DQS2_B_C  = M_C_CPU0_SB_DQS_DN<2>
  VSS56  = GND
  DQ20_B  = M_C_CPU0_SB_DQ<20>
  VSS57  = GND
  DQ21_B  = M_C_CPU0_SB_DQ<21>
  VSS58  = GND
  DQ24_B  = M_C_CPU0_SB_DQ<24>
  VSS59  = GND
  DQ25_B  = M_C_CPU0_SB_DQ<25>
  VSS60  = GND
  DQS3_B_T  = M_C_CPU0_SB_DQS_DP<3>
  DQS3_B_C  = M_C_CPU0_SB_DQS_DN<3>
  VSS61  = GND
  DQ28_B  = M_C_CPU0_SB_DQ<28>
  VSS62  = GND
  DQ29_B  = M_C_CPU0_SB_DQ<29>
  VSS63  = GND
  RFU1  = TP_CHC_CPU0_DIMM1_FRU_1
  VIN_BULK1  = P12V_S3_AUX_CPU0_NVDIMM
  VIN_BULK2  = P12V_S3_AUX_CPU0_NVDIMM
  \pwr_good||fail_n\  = PWRGD_CHC_CPU0_DIMM1
  HSA  = PD_CHC_CPU0_DIMM1_SAA
  RFU2  = TP_CHC_CPU0_DIMM1_FRU_2
  RFU3  = TP_CHC_CPU0_DIMM1_FRU_3
  VSS64  = GND
  DQ2_A  = M_C_CPU0_SA_DQ<2>
  VSS65  = GND
  DQ3_A  = M_C_CPU0_SA_DQ<3>
  VSS66  = GND
  \dqs5_a_c||tdqs5_a_c||dqs5_a_t||tdqs5_a_t\  = M_C_CPU0_SA_DQS_DN<5>
  \dqs5_a_t||tdqs5_a_t\  = M_C_CPU0_SA_DQS_DP<5>
  VSS67  = GND
  DQ6_A  = M_C_CPU0_SA_DQ<6>
  VSS68  = GND
  DQ7_A  = M_C_CPU0_SA_DQ<7>
  VSS69  = GND
  DQ10_A  = M_C_CPU0_SA_DQ<10>
  VSS70  = GND
  DQ11_A  = M_C_CPU0_SA_DQ<11>
  VSS71  = GND
  \dqs6_a_c||tdqs6_a_c||dqs6_a_t||tdqs6_a_t\  = M_C_CPU0_SA_DQS_DN<6>
  \dqs6_a_t||tdqs6_a_t\  = M_C_CPU0_SA_DQS_DP<6>
  VSS72  = GND
  DQ14_A  = M_C_CPU0_SA_DQ<14>
  VSS73  = GND
  DQ15_A  = M_C_CPU0_SA_DQ<15>
  VSS74  = GND
  DQ18_A  = M_C_CPU0_SA_DQ<18>
  VSS75  = GND
  DQ19_A  = M_C_CPU0_SA_DQ<19>
  VSS76  = GND
  \dqs7_a_c||tdqs7_a_c\  = M_C_CPU0_SA_DQS_DN<7>
  \dqs7_a_t||tdqs7_a_t\  = M_C_CPU0_SA_DQS_DP<7>
  VSS77  = GND
  DQ22_A  = M_C_CPU0_SA_DQ<22>
  VSS78  = GND
  DQ23_A  = M_C_CPU0_SA_DQ<23>
  VSS79  = GND
  DQ26_A  = M_C_CPU0_SA_DQ<26>
  VSS80  = GND
  DQ27_A  = M_C_CPU0_SA_DQ<27>
  VSS81  = GND
  \dqs8_a_c||tdqs8_a_c\  = M_C_CPU0_SA_DQS_DN<8>
  \dqs8_a_t||tdqs8_a_t\  = M_C_CPU0_SA_DQS_DP<8>
  VSS82  = GND
  DQ30_A  = M_C_CPU0_SA_DQ<30>
  VSS83  = GND
  DQ31_A  = M_C_CPU0_SA_DQ<31>
  VSS84  = GND
  CB2_A  = M_C_CPU0_SA_CB<2>
  VSS85  = GND
  CB3_A  = M_C_CPU0_SA_CB<3>
  VSS86  = GND
  \dqs9_a_c||tdqs9_a_c\  = M_C_CPU0_SA_DQS_DN<9>
  \dqs9_a_t||tdqs9_a_t\  = M_C_CPU0_SA_DQS_DP<9>
  VSS87  = GND
  CB6_A  = M_C_CPU0_SA_CB<6>
  VSS88  = GND
  CB7_A  = M_C_CPU0_SA_CB<7>
  VSS89  = GND
  RESET_N  = RST_M_CD_CPU0_FPGA_N
  VSS90  = GND
  CS1_A_N  = M_C_CPU0_SA_CS_N<1>
  VSS91  = GND
  CA1_A  = M_C_CPU0_SA_CA<1>
  VSS92  = GND
  CA3_A  = M_C_CPU0_SA_CA<3>
  VSS93  = GND
  CA5_A  = M_C_CPU0_SA_CA<5>
  VSS94  = GND
  CK_T  = M_C_CPU0_CLK_DP<0>
  CK_C  = M_C_CPU0_CLK_DN<0>
  VSS95  = GND
  RFU4  = TP_CHC_CPU0_DIMM1_FRU_4
  CA1_B  = M_C_CPU0_SB_CA<1>
  VSS96  = GND
  CA3_B  = M_C_CPU0_SB_CA<3>
  VSS97  = GND
  CA5_B  = M_C_CPU0_SB_CA<5>
  VSS98  = GND
  PAR_B  = M_C_CPU0_SB_PAR
  VSS99  = GND
  CS1_B_N  = M_C_CPU0_SB_CS_N<1>
  VSS100  = GND
  RFU5  = TP_CHC_CPU0_DIMM1_FRU_5
  RFU6  = TP_CHC_CPU0_DIMM1_FRU_6
  VSS101  = GND
  CB6_B  = M_C_CPU0_SB_CB<6>
  VSS102  = GND
  CB7_B  = M_C_CPU0_SB_CB<7>
  VSS103  = GND
  DQS4_B_C  = M_C_CPU0_SB_DQS_DN<4>
  DQS4_B_T  = M_C_CPU0_SB_DQS_DP<4>
  VSS104  = GND
  CB2_B  = M_C_CPU0_SB_CB<2>
  VSS105  = GND
  CB3_B  = M_C_CPU0_SB_CB<3>
  VSS106  = GND
  DQ2_B  = M_C_CPU0_SB_DQ<2>
  VSS107  = GND
  DQ3_B  = M_C_CPU0_SB_DQ<3>
  VSS108  = GND
  \dqs5_b_c||tdqs5_b_c\  = M_C_CPU0_SB_DQS_DN<5>
  \dqs5_b_t||tdqs5_b_t\  = M_C_CPU0_SB_DQS_DP<5>
  VSS109  = GND
  DQ6_B  = M_C_CPU0_SB_DQ<6>
  VSS110  = GND
  DQ7_B  = M_C_CPU0_SB_DQ<7>
  VSS111  = GND
  DQ10_B  = M_C_CPU0_SB_DQ<10>
  VSS112  = GND
  DQ11_B  = M_C_CPU0_SB_DQ<11>
  VSS113  = GND
  \dqs6_b_c||tdqs6_b_c\  = M_C_CPU0_SB_DQS_DN<6>
  \dqs6_b_t||tdqs6_b_t\  = M_C_CPU0_SB_DQS_DP<6>
  VSS114  = GND
  DQ14_B  = M_C_CPU0_SB_DQ<14>
  VSS115  = GND
  DQ15_B  = M_C_CPU0_SB_DQ<15>
  VSS116  = GND
  DQ18_B  = M_C_CPU0_SB_DQ<18>
  VSS117  = GND
  DQ19_B  = M_C_CPU0_SB_DQ<19>
  VSS118  = GND
  \dqs7_b_c||tdqs7_b_c\  = M_C_CPU0_SB_DQS_DN<7>
  \dqs7_b_t||tdqs7_b_t\  = M_C_CPU0_SB_DQS_DP<7>
  VSS119  = GND
  DQ22_B  = M_C_CPU0_SB_DQ<22>
  VSS120  = GND
  DQ23_B  = M_C_CPU0_SB_DQ<23>
  VSS121  = GND
  DQ26_B  = M_C_CPU0_SB_DQ<26>
  VSS122  = GND
  DQ27_B  = M_C_CPU0_SB_DQ<27>
  VSS123  = GND
  \dqs8_b_c||tdqs8_b_c\  = M_C_CPU0_SB_DQS_DN<8>
  \dqs8_b_t||tdqs8_b_t\  = M_C_CPU0_SB_DQS_DP<8>
  VSS124  = GND
  DQ30_B  = M_C_CPU0_SB_DQ<30>
  VSS125  = GND
  DQ31_B  = M_C_CPU0_SB_DQ<31>
  VSS126  = GND
  G1  = GND
  G2  = GND
  G3  = GND

(kicad_pcb
	(version 20260206)
	(generator "pcbnew")
	(generator_version "10.0")
	(general
		(thickness 1.6)
		(legacy_teardrops no)
	)
	(paper "A4")
	(title_block
		(title "03242023_DA0F0TMBIJ0_F0T_Motherboard_J_brd_V01_OCP.brd")
		(comment 1 "Grand Teton / footprint 885 of 6105 (J5), pads 138-182 of 291")
	)
	(layers
		(0 "F.Cu" signal "TOP")
		(4 "In1.Cu" signal "GND")
		(6 "In2.Cu" signal "IN1")
		(8 "In3.Cu" signal "GND1")
		(10 "In4.Cu" signal "IN2")
		(12 "In5.Cu" signal "GND2")
		(14 "In6.Cu" signal "IN3")
		(16 "In7.Cu" signal "GND3")
		(18 "In8.Cu" signal "VCC")
		(20 "In9.Cu" signal "VCC1")
		(22 "In10.Cu" signal "GND4")
		(24 "In11.Cu" signal "IN4")
		(26 "In12.Cu" signal "GND5")
		(28 "In13.Cu" signal "IN5")
		(30 "In14.Cu" signal "GND6")
		(32 "In15.Cu" signal "IN6")
		(34 "In16.Cu" signal "GND7")
		(2 "B.Cu" signal "BOTTOM")
		(9 "F.Adhes" user "F.Adhesive")
		(11 "B.Adhes" user "B.Adhesive")
		(13 "F.Paste" user "Package Geometry/Pastemask Top")
		(15 "B.Paste" user "Package Geometry/Pastemask Bottom")
		(5 "F.SilkS" user "Ref Des/Silkscreen Top")
		(7 "B.SilkS" user "Ref Des/Silkscreen Bottom")
		(1 "F.Mask" user "Board Geometry/Soldermask Top")
		(3 "B.Mask" user "Board Geometry/Soldermask Bottom")
		(17 "Dwgs.User" user "User.Drawings")
		(19 "Cmts.User" user "User.Comments")
		(21 "Eco1.User" user "User.Eco1")
		(23 "Eco2.User" user "User.Eco2")
		(25 "Edge.Cuts" user "Board Geometry/Outline")
		(27 "Margin" user)
		(31 "F.CrtYd" user "Package Geometry/Place Bound Top")
		(29 "B.CrtYd" user "Package Geometry/Place Bound Bottom")
		(35 "F.Fab" user "Ref Des/Assembly Top")
		(33 "B.Fab" user "Ref Des/Assembly Bottom")
	)
	(footprint ""
		(layer "F.Cu")
		(at 273.218148 -258.091686)
		(property "Reference" "J5"
			(at -3.683 -81.702148 0)
			(unlocked yes)
			(layer "F.SilkS")
			(effects
				(font
					(size 0.7874 0.5842)
					(thickness 0.1524)
				)
				(justify left)
			)
		)
		(property "Value" ""
			(at 0 0 0)
			(layer "F.Fab")
			(effects
				(font
					(size 1.27 1.27)
				)
			)
		)
		(duplicate_pad_numbers_are_jumpers no)
		(pad "138" smd rect
			(at -2.050034 58.224928 270)
			(size 0.519938 1.4986)
			(layers "F.Cu" "F.Mask" "F.Paste")
			(net "M_C_CPU0_SB_DQS_DN<3>")
		)
		(pad "139" smd rect
			(at -2.050034 59.075066 270)
			(size 0.519938 1.4986)
			(layers "F.Cu" "F.Mask" "F.Paste")
			(net "GND")
		)
		(pad "140" smd rect
			(at -2.050034 59.92495 270)
			(size 0.519938 1.4986)
			(layers "F.Cu" "F.Mask" "F.Paste")
			(net "M_C_CPU0_SB_DQ<28>")
		)
		(pad "141" smd rect
			(at -2.050034 60.775088 270)
			(size 0.519938 1.4986)
			(layers "F.Cu" "F.Mask" "F.Paste")
			(net "GND")
		)
		(pad "142" smd rect
			(at -2.050034 61.624972 270)
			(size 0.519938 1.4986)
			(layers "F.Cu" "F.Mask" "F.Paste")
			(net "M_C_CPU0_SB_DQ<29>")
		)
		(pad "143" smd rect
			(at -2.050034 62.47511 270)
			(size 0.519938 1.4986)
			(layers "F.Cu" "F.Mask" "F.Paste")
			(net "GND")
		)
		(pad "144" smd rect
			(at -2.050034 63.324994 270)
			(size 0.519938 1.4986)
			(layers "F.Cu" "F.Mask" "F.Paste")
			(net "TP_CHC_CPU0_DIMM1_FRU_1")
		)
		(pad "145" smd rect
			(at 2.050034 -63.324994 270)
			(size 0.519938 1.4986)
			(layers "F.Cu" "F.Mask" "F.Paste")
			(net "P12V_S3_AUX_CPU0_NVDIMM")
		)
		(pad "146" smd rect
			(at 2.050034 -62.47511 270)
			(size 0.519938 1.4986)
			(layers "F.Cu" "F.Mask" "F.Paste")
			(net "P12V_S3_AUX_CPU0_NVDIMM")
		)
		(pad "147" smd rect
			(at 2.050034 -61.624972 270)
			(size 0.519938 1.4986)
			(layers "F.Cu" "F.Mask" "F.Paste")
			(net "PWRGD_CHC_CPU0_DIMM1")
		)
		(pad "148" smd rect
			(at 2.050034 -60.775088 270)
			(size 0.519938 1.4986)
			(layers "F.Cu" "F.Mask" "F.Paste")
			(net "PD_CHC_CPU0_DIMM1_SAA")
		)
		(pad "149" smd rect
			(at 2.050034 -59.92495 270)
			(size 0.519938 1.4986)
			(layers "F.Cu" "F.Mask" "F.Paste")
			(net "TP_CHC_CPU0_DIMM1_FRU_2")
		)
		(pad "150" smd rect
			(at 2.050034 -59.075066 270)
			(size 0.519938 1.4986)
			(layers "F.Cu" "F.Mask" "F.Paste")
			(net "TP_CHC_CPU0_DIMM1_FRU_3")
		)
		(pad "151" smd rect
			(at 2.050034 -58.224928 270)
			(size 0.519938 1.4986)
			(layers "F.Cu" "F.Mask" "F.Paste")
			(net "GND")
		)
		(pad "152" smd rect
			(at 2.050034 -57.375044 270)
			(size 0.519938 1.4986)
			(layers "F.Cu" "F.Mask" "F.Paste")
			(net "M_C_CPU0_SA_DQ<2>")
		)
		(pad "153" smd rect
			(at 2.050034 -56.524906 270)
			(size 0.519938 1.4986)
			(layers "F.Cu" "F.Mask" "F.Paste")
			(net "GND")
		)
		(pad "154" smd rect
			(at 2.050034 -55.675022 270)
			(size 0.519938 1.4986)
			(layers "F.Cu" "F.Mask" "F.Paste")
			(net "M_C_CPU0_SA_DQ<3>")
		)
		(pad "155" smd rect
			(at 2.050034 -54.824884 270)
			(size 0.519938 1.4986)
			(layers "F.Cu" "F.Mask" "F.Paste")
			(net "GND")
		)
		(pad "156" smd rect
			(at 2.050034 -53.975 270)
			(size 0.519938 1.4986)
			(layers "F.Cu" "F.Mask" "F.Paste")
			(net "M_C_CPU0_SA_DQS_DN<5>")
		)
		(pad "157" smd rect
			(at 2.050034 -53.125116 270)
			(size 0.519938 1.4986)
			(layers "F.Cu" "F.Mask" "F.Paste")
			(net "M_C_CPU0_SA_DQS_DP<5>")
		)
		(pad "158" smd rect
			(at 2.050034 -52.274978 270)
			(size 0.519938 1.4986)
			(layers "F.Cu" "F.Mask" "F.Paste")
			(net "GND")
		)
		(pad "159" smd rect
			(at 2.050034 -51.425094 270)
			(size 0.519938 1.4986)
			(layers "F.Cu" "F.Mask" "F.Paste")
			(net "M_C_CPU0_SA_DQ<6>")
		)
		(pad "160" smd rect
			(at 2.050034 -50.574956 270)
			(size 0.519938 1.4986)
			(layers "F.Cu" "F.Mask" "F.Paste")
			(net "GND")
		)
		(pad "161" smd rect
			(at 2.050034 -49.725072 270)
			(size 0.519938 1.4986)
			(layers "F.Cu" "F.Mask" "F.Paste")
			(net "M_C_CPU0_SA_DQ<7>")
		)
		(pad "162" smd rect
			(at 2.050034 -48.874934 270)
			(size 0.519938 1.4986)
			(layers "F.Cu" "F.Mask" "F.Paste")
			(net "GND")
		)
		(pad "163" smd rect
			(at 2.050034 -48.02505 270)
			(size 0.519938 1.4986)
			(layers "F.Cu" "F.Mask" "F.Paste")
			(net "M_C_CPU0_SA_DQ<10>")
		)
		(pad "164" smd rect
			(at 2.050034 -47.174912 270)
			(size 0.519938 1.4986)
			(layers "F.Cu" "F.Mask" "F.Paste")
			(net "GND")
		)
		(pad "165" smd rect
			(at 2.050034 -46.325028 270)
			(size 0.519938 1.4986)
			(layers "F.Cu" "F.Mask" "F.Paste")
			(net "M_C_CPU0_SA_DQ<11>")
		)
		(pad "166" smd rect
			(at 2.050034 -45.47489 270)
			(size 0.519938 1.4986)
			(layers "F.Cu" "F.Mask" "F.Paste")
			(net "GND")
		)
		(pad "167" smd rect
			(at 2.050034 -44.625006 270)
			(size 0.519938 1.4986)
			(layers "F.Cu" "F.Mask" "F.Paste")
			(net "M_C_CPU0_SA_DQS_DN<6>")
		)
		(pad "168" smd rect
			(at 2.050034 -43.775122 270)
			(size 0.519938 1.4986)
			(layers "F.Cu" "F.Mask" "F.Paste")
			(net "M_C_CPU0_SA_DQS_DP<6>")
		)
		(pad "169" smd rect
			(at 2.050034 -42.924984 270)
			(size 0.519938 1.4986)
			(layers "F.Cu" "F.Mask" "F.Paste")
			(net "GND")
		)
		(pad "170" smd rect
			(at 2.050034 -42.0751 270)
			(size 0.519938 1.4986)
			(layers "F.Cu" "F.Mask" "F.Paste")
			(net "M_C_CPU0_SA_DQ<14>")
		)
		(pad "171" smd rect
			(at 2.050034 -41.224962 270)
			(size 0.519938 1.4986)
			(layers "F.Cu" "F.Mask" "F.Paste")
			(net "GND")
		)
		(pad "172" smd rect
			(at 2.050034 -40.375078 270)
			(size 0.519938 1.4986)
			(layers "F.Cu" "F.Mask" "F.Paste")
			(net "M_C_CPU0_SA_DQ<15>")
		)
		(pad "173" smd rect
			(at 2.050034 -39.52494 270)
			(size 0.519938 1.4986)
			(layers "F.Cu" "F.Mask" "F.Paste")
			(net "GND")
		)
		(pad "174" smd rect
			(at 2.050034 -38.675056 270)
			(size 0.519938 1.4986)
			(layers "F.Cu" "F.Mask" "F.Paste")
			(net "M_C_CPU0_SA_DQ<18>")
		)
		(pad "175" smd rect
			(at 2.050034 -37.824918 270)
			(size 0.519938 1.4986)
			(layers "F.Cu" "F.Mask" "F.Paste")
			(net "GND")
		)
		(pad "176" smd rect
			(at 2.050034 -36.975034 270)
			(size 0.519938 1.4986)
			(layers "F.Cu" "F.Mask" "F.Paste")
			(net "M_C_CPU0_SA_DQ<19>")
		)
		(pad "177" smd rect
			(at 2.050034 -36.124896 270)
			(size 0.519938 1.4986)
			(layers "F.Cu" "F.Mask" "F.Paste")
			(net "GND")
		)
		(pad "178" smd rect
			(at 2.050034 -35.275012 270)
			(size 0.519938 1.4986)
			(layers "F.Cu" "F.Mask" "F.Paste")
			(net "M_C_CPU0_SA_DQS_DN<7>")
		)
		(pad "179" smd rect
			(at 2.050034 -34.425128 270)
			(size 0.519938 1.4986)
			(layers "F.Cu" "F.Mask" "F.Paste")
			(net "M_C_CPU0_SA_DQS_DP<7>")
		)
		(pad "180" smd rect
			(at 2.050034 -33.57499 270)
			(size 0.519938 1.4986)
			(layers "F.Cu" "F.Mask" "F.Paste")
			(net "GND")
		)
		(pad "181" smd rect
			(at 2.050034 -32.725106 270)
			(size 0.519938 1.4986)
			(layers "F.Cu" "F.Mask" "F.Paste")
			(net "M_C_CPU0_SA_DQ<22>")
		)
		(pad "182" smd rect
			(at 2.050034 -31.874968 270)
			(size 0.519938 1.4986)
			(layers "F.Cu" "F.Mask" "F.Paste")
			(net "GND")
		)
	)
)
